# BASEBOARD_FAB2 (Tioga Pass) — schematic netlist excerpt (pin names and nets, part order shuffled) for the footprints in the layout excerpt that follows; sources: Cadence DE-HDL packaged netlist, KiCad conversion of Wiwynn_Tioga_Pass_MB.brd

C2U24  CAP_A  0.1UF 16V 10% X7R  pkg 0402V  page 108 : A = P12V ; B = GND
C2L46  CAPP  470UF 2V 20% ALUM  pkg SM  page 236 : A = P1V05_PCH_STBY ; B = GND
C3P27  CAP  0.22UF 16V 10% X7R  pkg 0402  page 107 : A = P3E_CPU0_PE1_SS_TXP<4> ; B = P3E_CPU0_PE1_PCH_TXP<4>

(kicad_pcb
	(version 20260206)
	(generator "pcbnew")
	(generator_version "10.0")
	(general
		(thickness 1.6)
		(legacy_teardrops no)
	)
	(paper "A4")
	(title_block
		(title "Wiwynn_Tioga_Pass_MB.brd")
		(comment 1 "Tioga Pass / footprints 3682-3684 of 4770")
	)
	(layers
		(0 "F.Cu" signal "TOP")
		(4 "In1.Cu" signal "L2GND")
		(6 "In2.Cu" signal "L3")
		(8 "In3.Cu" signal "L4GND")
		(10 "In4.Cu" signal "L5")
		(12 "In5.Cu" signal "L6GND")
		(14 "In6.Cu" signal "L7VCC")
		(16 "In7.Cu" signal "L8VCC")
		(18 "In8.Cu" signal "L9GND")
		(20 "In9.Cu" signal "L10")
		(22 "In10.Cu" signal "L11GND")
		(24 "In11.Cu" signal "L12")
		(26 "In12.Cu" signal "L13GND")
		(2 "B.Cu" signal "BOTTOM")
		(9 "F.Adhes" user "F.Adhesive")
		(11 "B.Adhes" user "B.Adhesive")
		(13 "F.Paste" user "Package Geometry/Pastemask Top")
		(15 "B.Paste" user "Package Geometry/Pastemask Bottom")
		(5 "F.SilkS" user "Ref Des/Silkscreen Top")
		(7 "B.SilkS" user "Ref Des/Silkscreen Bottom")
		(1 "F.Mask" user "Board Geometry/Soldermask Top")
		(3 "B.Mask" user "Board Geometry/Soldermask Bottom")
		(17 "Dwgs.User" user "User.Drawings")
		(19 "Cmts.User" user "User.Comments")
		(21 "Eco1.User" user "User.Eco1")
		(23 "Eco2.User" user "User.Eco2")
		(25 "Edge.Cuts" user "Board Geometry/Outline")
		(27 "Margin" user)
		(31 "F.CrtYd" user "Package Geometry/Place Bound Top")
		(29 "B.CrtYd" user "Package Geometry/Place Bound Bottom")
		(35 "F.Fab" user "Ref Des/Assembly Top")
		(33 "B.Fab" user "Ref Des/Assembly Bottom")
	)
	(footprint ""
		(layer "B.Cu")
		(at 470.379044 -4.56692 -90)
		(property "Reference" "C2U24"
			(at 0 0 90)
			(layer "B.SilkS")
			(hide yes)
			(effects
				(font
					(size 1.27 1.27)
				)
				(justify mirror)
			)
		)
		(property "Value" ""
			(at 0 0 90)
			(layer "B.Fab")
			(effects
				(font
					(size 1.27 1.27)
				)
				(justify mirror)
			)
		)
		(duplicate_pad_numbers_are_jumpers no)
		(fp_poly
			(pts
				(xy -0.3048 -0.1016) (xy -0.3048 0.9906) (xy 0.3048 0.9906) (xy 0.3048 -0.1016)
			)
			(stroke
				(width 0)
				(type default)
			)
			(fill no)
			(layer "B.CrtYd")
		)
		(fp_line
			(start -0.3048 0.9906)
			(end -0.3048 -0.1016)
			(stroke
				(width 0.1)
				(type default)
			)
			(layer "B.Fab")
		)
		(fp_line
			(start 0.3048 0.9906)
			(end -0.3048 0.9906)
			(stroke
				(width 0.1)
				(type default)
			)
			(layer "B.Fab")
		)
		(fp_line
			(start -0.3048 -0.1016)
			(end 0.3048 -0.1016)
			(stroke
				(width 0.1)
				(type default)
			)
			(layer "B.Fab")
		)
		(fp_line
			(start 0.3048 -0.1016)
			(end 0.3048 0.9906)
			(stroke
				(width 0.1)
				(type default)
			)
			(layer "B.Fab")
		)
		(pad "1" smd rect
			(at 0 0 90)
			(size 0.508 0.508)
			(layers "B.Cu" "B.Mask" "B.Paste")
			(net "P12V")
		)
		(pad "2" smd rect
			(at 0 0.889 90)
			(size 0.508 0.508)
			(layers "B.Cu" "B.Mask" "B.Paste")
			(net "GND")
		)
		(zone
			(layer "B.Cu")
			(hatch none 0.5)
			(connect_pads
				(clearance 0)
			)
			(min_thickness 0.25)
			(keepout
				(tracks not_allowed)
				(vias allowed)
				(pads allowed)
				(copperpour not_allowed)
				(footprints allowed)
			)
			(placement
				(enabled no)
				(sheetname "")
			)
			(fill
				(thermal_gap 0.5)
				(thermal_bridge_width 0.5)
				(island_removal_mode 0)
			)
			(polygon
				(pts
					(xy 469.744044 -4.31292) (xy 469.744044 -4.82092) (xy 470.125044 -4.82092) (xy 470.125044 -4.31292)
				)
			)
		)
		(zone
			(layer "B.Cu")
			(hatch none 0.5)
			(connect_pads
				(clearance 0)
			)
			(min_thickness 0.25)
			(keepout
				(tracks allowed)
				(vias not_allowed)
				(pads allowed)
				(copperpour not_allowed)
				(footprints allowed)
			)
			(placement
				(enabled no)
				(sheetname "")
			)
			(fill
				(thermal_gap 0.5)
				(thermal_bridge_width 0.5)
				(island_removal_mode 0)
			)
			(polygon
				(pts
					(xy 470.125044 -4.31292) (xy 470.125044 -4.82092) (xy 469.744044 -4.82092) (xy 469.744044 -4.31292)
				)
			)
		)
	)
	(footprint ""
		(layer "B.Cu")
		(at 350.024192 -77.834236 180)
		(property "Reference" "C3P27"
			(at 0 0 0)
			(layer "B.SilkS")
			(hide yes)
			(effects
				(font
					(size 1.27 1.27)
				)
				(justify mirror)
			)
		)
		(property "Value" ""
			(at 0 0 0)
			(layer "B.Fab")
			(effects
				(font
					(size 1.27 1.27)
				)
				(justify mirror)
			)
		)
		(duplicate_pad_numbers_are_jumpers no)
		(fp_poly
			(pts
				(xy -0.3048 -0.1016) (xy -0.3048 0.9906) (xy 0.3048 0.9906) (xy 0.3048 -0.1016)
			)
			(stroke
				(width 0)
				(type default)
			)
			(fill no)
			(layer "B.CrtYd")
		)
		(fp_line
			(start 0.3048 0.9906)
			(end -0.3048 0.9906)
			(stroke
				(width 0.1)
				(type default)
			)
			(layer "B.Fab")
		)
		(fp_line
			(start 0.3048 -0.1016)
			(end 0.3048 0.9906)
			(stroke
				(width 0.1)
				(type default)
			)
			(layer "B.Fab")
		)
		(fp_line
			(start -0.3048 0.9906)
			(end -0.3048 -0.1016)
			(stroke
				(width 0.1)
				(type default)
			)
			(layer "B.Fab")
		)
		(fp_line
			(start -0.3048 -0.1016)
			(end 0.3048 -0.1016)
			(stroke
				(width 0.1)
				(type default)
			)
			(layer "B.Fab")
		)
		(pad "1" smd rect
			(at 0 0)
			(size 0.508 0.508)
			(layers "B.Cu" "B.Mask" "B.Paste")
			(net "P3E_CPU0_PE1_SS_TXP<4>")
		)
		(pad "2" smd rect
			(at 0 0.889)
			(size 0.508 0.508)
			(layers "B.Cu" "B.Mask" "B.Paste")
			(net "P3E_CPU0_PE1_PCH_TXP<4>")
		)
		(zone
			(layer "B.Cu")
			(hatch none 0.5)
			(connect_pads
				(clearance 0)
			)
			(min_thickness 0.25)
			(keepout
				(tracks not_allowed)
				(vias allowed)
				(pads allowed)
				(copperpour not_allowed)
				(footprints allowed)
			)
			(placement
				(enabled no)
				(sheetname "")
			)
			(fill
				(thermal_gap 0.5)
				(thermal_bridge_width 0.5)
				(island_removal_mode 0)
			)
			(polygon
				(pts
					(xy 349.770192 -78.469236) (xy 350.278192 -78.469236) (xy 350.278192 -78.088236) (xy 349.770192 -78.088236)
				)
			)
		)
		(zone
			(layer "B.Cu")
			(hatch none 0.5)
			(connect_pads
				(clearance 0)
			)
			(min_thickness 0.25)
			(keepout
				(tracks allowed)
				(vias not_allowed)
				(pads allowed)
				(copperpour not_allowed)
				(footprints allowed)
			)
			(placement
				(enabled no)
				(sheetname "")
			)
			(fill
				(thermal_gap 0.5)
				(thermal_bridge_width 0.5)
				(island_removal_mode 0)
			)
			(polygon
				(pts
					(xy 349.770192 -78.088236) (xy 350.278192 -78.088236) (xy 350.278192 -78.469236) (xy 349.770192 -78.469236)
				)
			)
		)
	)
	(footprint ""
		(layer "B.Cu")
		(at 396.06982 -139.69238 180)
		(property "Reference" "C2L46"
			(at -3.10007 3.24612 270)
			(unlocked yes)
			(layer "B.SilkS")
			(effects
				(font
					(size 0.7874 0.5842)
					(thickness 0.1524)
				)
				(justify mirror)
			)
		)
		(property "Value" ""
			(at 0 0 0)
			(layer "B.Fab")
			(effects
				(font
					(size 1.27 1.27)
				)
				(justify mirror)
			)
		)
		(duplicate_pad_numbers_are_jumpers no)
		(fp_line
			(start 2.563114 1.633728)
			(end 1.6002 1.633728)
			(stroke
				(width 0.1524)
				(type default)
			)
			(layer "B.SilkS")
		)
		(fp_line
			(start 2.563114 -1.616456)
			(end 2.563114 1.633728)
			(stroke
				(width 0.1524)
				(type default)
			)
			(layer "B.SilkS")
		)
		(fp_line
			(start 2.286 7.366)
			(end 2.286 1.632712)
			(stroke
				(width 0.1524)
				(type default)
			)
			(layer "B.SilkS")
		)
		(fp_line
			(start 2.286 7.366)
			(end 1.60147 7.366)
			(stroke
				(width 0.1524)
				(type default)
			)
			(layer "B.SilkS")
		)
		(fp_line
			(start 1.6002 -1.616456)
			(end 2.563114 -1.616456)
			(stroke
				(width 0.1524)
				(type default)
			)
			(layer "B.SilkS")
		)
		(fp_line
			(start -1.6002 -1.616456)
			(end -2.504948 -1.616456)
			(stroke
				(width 0.1524)
				(type default)
			)
			(layer "B.SilkS")
		)
		(fp_line
			(start -2.286 7.366)
			(end -1.600708 7.366)
			(stroke
				(width 0.1524)
				(type default)
			)
			(layer "B.SilkS")
		)
		(fp_line
			(start -2.286 7.366)
			(end -2.286 1.63195)
			(stroke
				(width 0.1524)
				(type default)
			)
			(layer "B.SilkS")
		)
		(fp_line
			(start -2.504948 1.633728)
			(end -1.6002 1.633728)
			(stroke
				(width 0.1524)
				(type default)
			)
			(layer "B.SilkS")
		)
		(fp_line
			(start -2.504948 -1.616456)
			(end -2.504948 1.633728)
			(stroke
				(width 0.1524)
				(type default)
			)
			(layer "B.SilkS")
		)
		(fp_rect
			(start 2.286 7.366)
			(end -2.286 -0.254)
			(stroke
				(width 0)
				(type default)
			)
			(fill no)
			(layer "B.CrtYd")
		)
		(fp_line
			(start 2.286 7.366)
			(end 2.286 -0.254)
			(stroke
				(width 0.1)
				(type default)
			)
			(layer "B.Fab")
		)
		(fp_line
			(start 2.286 -0.254)
			(end -2.286 -0.254)
			(stroke
				(width 0.1)
				(type default)
			)
			(layer "B.Fab")
		)
		(fp_line
			(start -2.286 7.366)
			(end 2.286 7.366)
			(stroke
				(width 0.1)
				(type default)
			)
			(layer "B.Fab")
		)
		(fp_line
			(start -2.286 -0.254)
			(end -2.286 7.366)
			(stroke
				(width 0.1)
				(type default)
			)
			(layer "B.Fab")
		)
		(pad "1" smd rect
			(at 0 0)
			(size 2.54 3.048)
			(layers "B.Cu" "B.Mask" "B.Paste")
			(net "P1V05_PCH_STBY")
		)
		(pad "2" smd rect
			(at 0 7.112)
			(size 2.54 3.048)
			(layers "B.Cu" "B.Mask" "B.Paste")
			(net "GND")
		)
	)
)
